# S9S_MB_2U (Grand Teton) — schematic netlist excerpt (pin names and nets, part order shuffled) for the footprints in the layout excerpt that follows; sources: Cadence DE-HDL packaged netlist, KiCad conversion of 03242023_DA0F0TMBIJ0_F0T_Motherboard_J_brd_V01_OCP.brd

R4645  Q_RES  1K 1% EMPTY  pkg 0402LF  page 167 : A = P3V3_AUX ; B = FM_P2E_BUF2_EQB0
R4736  Q_RES  0 5% CHIP  pkg 0402LF  page 227 : A = PRSNT_CABLE_GPU_A2_ISO_N ; B = PRSNT_CABLE_GPU_A2_ISO_R1_N

(kicad_pcb
	(version 20260206)
	(generator "pcbnew")
	(generator_version "10.0")
	(general
		(thickness 1.6)
		(legacy_teardrops no)
	)
	(paper "A4")
	(title_block
		(title "03242023_DA0F0TMBIJ0_F0T_Motherboard_J_brd_V01_OCP.brd")
		(comment 1 "Grand Teton / footprints 644-645 of 6105")
	)
	(layers
		(0 "F.Cu" signal "TOP")
		(4 "In1.Cu" signal "GND")
		(6 "In2.Cu" signal "IN1")
		(8 "In3.Cu" signal "GND1")
		(10 "In4.Cu" signal "IN2")
		(12 "In5.Cu" signal "GND2")
		(14 "In6.Cu" signal "IN3")
		(16 "In7.Cu" signal "GND3")
		(18 "In8.Cu" signal "VCC")
		(20 "In9.Cu" signal "VCC1")
		(22 "In10.Cu" signal "GND4")
		(24 "In11.Cu" signal "IN4")
		(26 "In12.Cu" signal "GND5")
		(28 "In13.Cu" signal "IN5")
		(30 "In14.Cu" signal "GND6")
		(32 "In15.Cu" signal "IN6")
		(34 "In16.Cu" signal "GND7")
		(2 "B.Cu" signal "BOTTOM")
		(9 "F.Adhes" user "F.Adhesive")
		(11 "B.Adhes" user "B.Adhesive")
		(13 "F.Paste" user "Package Geometry/Pastemask Top")
		(15 "B.Paste" user "Package Geometry/Pastemask Bottom")
		(5 "F.SilkS" user "Ref Des/Silkscreen Top")
		(7 "B.SilkS" user "Ref Des/Silkscreen Bottom")
		(1 "F.Mask" user "Board Geometry/Soldermask Top")
		(3 "B.Mask" user "Board Geometry/Soldermask Bottom")
		(17 "Dwgs.User" user "User.Drawings")
		(19 "Cmts.User" user "User.Comments")
		(21 "Eco1.User" user "User.Eco1")
		(23 "Eco2.User" user "User.Eco2")
		(25 "Edge.Cuts" user "Board Geometry/Outline")
		(27 "Margin" user)
		(31 "F.CrtYd" user "Package Geometry/Place Bound Top")
		(29 "B.CrtYd" user "Package Geometry/Place Bound Bottom")
		(35 "F.Fab" user "Ref Des/Assembly Top")
		(33 "B.Fab" user "Ref Des/Assembly Bottom")
	)
	(footprint ""
		(layer "F.Cu")
		(at 49.3903 -389.985758 180)
		(property "Reference" "R4645"
			(at 0 0 180)
			(layer "F.SilkS")
			(hide yes)
			(effects
				(font
					(size 1.27 1.27)
				)
			)
		)
		(property "Value" ""
			(at 0 0 180)
			(layer "F.Fab")
			(effects
				(font
					(size 1.27 1.27)
				)
			)
		)
		(duplicate_pad_numbers_are_jumpers no)
		(fp_line
			(start 0.7874 0.4064)
			(end -0.7874 0.4064)
			(stroke
				(width 0.1524)
				(type default)
			)
			(layer "F.SilkS")
		)
		(fp_line
			(start 0.7874 -0.4064)
			(end 0.7874 0.4064)
			(stroke
				(width 0.1524)
				(type default)
			)
			(layer "F.SilkS")
		)
		(fp_line
			(start -0.7874 0.4064)
			(end -0.7874 -0.4064)
			(stroke
				(width 0.1524)
				(type default)
			)
			(layer "F.SilkS")
		)
		(fp_line
			(start -0.7874 -0.4064)
			(end 0.7874 -0.4064)
			(stroke
				(width 0.1524)
				(type default)
			)
			(layer "F.SilkS")
		)
		(fp_line
			(start 0.67945 0.3048)
			(end 0.120396 0.3048)
			(stroke
				(width 0.1)
				(type default)
			)
			(layer "F.Fab")
		)
		(fp_line
			(start 0.67945 -0.3048)
			(end 0.67945 0.3048)
			(stroke
				(width 0.1)
				(type default)
			)
			(layer "F.Fab")
		)
		(fp_line
			(start 0.12065 -0.2794)
			(end 0.12065 -0.3048)
			(stroke
				(width 0.1)
				(type default)
			)
			(layer "F.Fab")
		)
		(fp_line
			(start 0.12065 -0.3048)
			(end 0.67945 -0.3048)
			(stroke
				(width 0.1)
				(type default)
			)
			(layer "F.Fab")
		)
		(fp_line
			(start 0.120396 0.3048)
			(end 0.120396 0.2794)
			(stroke
				(width 0.1)
				(type default)
			)
			(layer "F.Fab")
		)
		(fp_line
			(start 0.120396 0.2794)
			(end -0.12065 0.2794)
			(stroke
				(width 0.1)
				(type default)
			)
			(layer "F.Fab")
		)
		(fp_line
			(start -0.12065 0.3048)
			(end -0.67945 0.3048)
			(stroke
				(width 0.1)
				(type default)
			)
			(layer "F.Fab")
		)
		(fp_line
			(start -0.12065 0.2794)
			(end -0.12065 0.3048)
			(stroke
				(width 0.1)
				(type default)
			)
			(layer "F.Fab")
		)
		(fp_line
			(start -0.12065 -0.2794)
			(end 0.12065 -0.2794)
			(stroke
				(width 0.1)
				(type default)
			)
			(layer "F.Fab")
		)
		(fp_line
			(start -0.12065 -0.305054)
			(end -0.12065 -0.2794)
			(stroke
				(width 0.1)
				(type default)
			)
			(layer "F.Fab")
		)
		(fp_line
			(start -0.67945 0.3048)
			(end -0.67945 -0.305054)
			(stroke
				(width 0.1)
				(type default)
			)
			(layer "F.Fab")
		)
		(fp_line
			(start -0.67945 -0.305054)
			(end -0.12065 -0.305054)
			(stroke
				(width 0.1)
				(type default)
			)
			(layer "F.Fab")
		)
		(pad "1" smd circle
			(at -0.40005 0 180)
			(size 0 0)
			(layers "F.Cu" "F.Mask" "F.Paste")
			(net "P3V3_AUX")
		)
		(pad "2" smd circle
			(at 0.40005 0 180)
			(size 0 0)
			(layers "F.Cu" "F.Mask" "F.Paste")
			(net "FM_P2E_BUF2_EQB0")
		)
	)
	(footprint ""
		(layer "F.Cu")
		(at 24.892 -419.5572 180)
		(property "Reference" "R4736"
			(at 0 0 180)
			(layer "F.SilkS")
			(hide yes)
			(effects
				(font
					(size 1.27 1.27)
				)
			)
		)
		(property "Value" ""
			(at 0 0 180)
			(layer "F.Fab")
			(effects
				(font
					(size 1.27 1.27)
				)
			)
		)
		(duplicate_pad_numbers_are_jumpers no)
		(fp_line
			(start 0.7874 0.4064)
			(end -0.7874 0.4064)
			(stroke
				(width 0.1524)
				(type default)
			)
			(layer "F.SilkS")
		)
		(fp_line
			(start 0.7874 -0.4064)
			(end 0.7874 0.4064)
			(stroke
				(width 0.1524)
				(type default)
			)
			(layer "F.SilkS")
		)
		(fp_line
			(start -0.7874 0.4064)
			(end -0.7874 -0.4064)
			(stroke
				(width 0.1524)
				(type default)
			)
			(layer "F.SilkS")
		)
		(fp_line
			(start -0.7874 -0.4064)
			(end 0.7874 -0.4064)
			(stroke
				(width 0.1524)
				(type default)
			)
			(layer "F.SilkS")
		)
		(fp_line
			(start 0.67945 0.3048)
			(end 0.120396 0.3048)
			(stroke
				(width 0.1)
				(type default)
			)
			(layer "F.Fab")
		)
		(fp_line
			(start 0.67945 -0.3048)
			(end 0.67945 0.3048)
			(stroke
				(width 0.1)
				(type default)
			)
			(layer "F.Fab")
		)
		(fp_line
			(start 0.12065 -0.2794)
			(end 0.12065 -0.3048)
			(stroke
				(width 0.1)
				(type default)
			)
			(layer "F.Fab")
		)
		(fp_line
			(start 0.12065 -0.3048)
			(end 0.67945 -0.3048)
			(stroke
				(width 0.1)
				(type default)
			)
			(layer "F.Fab")
		)
		(fp_line
			(start 0.120396 0.3048)
			(end 0.120396 0.2794)
			(stroke
				(width 0.1)
				(type default)
			)
			(layer "F.Fab")
		)
		(fp_line
			(start 0.120396 0.2794)
			(end -0.12065 0.2794)
			(stroke
				(width 0.1)
				(type default)
			)
			(layer "F.Fab")
		)
		(fp_line
			(start -0.12065 0.3048)
			(end -0.67945 0.3048)
			(stroke
				(width 0.1)
				(type default)
			)
			(layer "F.Fab")
		)
		(fp_line
			(start -0.12065 0.2794)
			(end -0.12065 0.3048)
			(stroke
				(width 0.1)
				(type default)
			)
			(layer "F.Fab")
		)
		(fp_line
			(start -0.12065 -0.2794)
			(end 0.12065 -0.2794)
			(stroke
				(width 0.1)
				(type default)
			)
			(layer "F.Fab")
		)
		(fp_line
			(start -0.12065 -0.305054)
			(end -0.12065 -0.2794)
			(stroke
				(width 0.1)
				(type default)
			)
			(layer "F.Fab")
		)
		(fp_line
			(start -0.67945 0.3048)
			(end -0.67945 -0.305054)
			(stroke
				(width 0.1)
				(type default)
			)
			(layer "F.Fab")
		)
		(fp_line
			(start -0.67945 -0.305054)
			(end -0.12065 -0.305054)
			(stroke
				(width 0.1)
				(type default)
			)
			(layer "F.Fab")
		)
		(pad "1" smd circle
			(at -0.40005 0 180)
			(size 0 0)
			(layers "F.Cu" "F.Mask" "F.Paste")
			(net "PRSNT_CABLE_GPU_A2_ISO_N")
		)
		(pad "2" smd circle
			(at 0.40005 0 180)
			(size 0 0)
			(layers "F.Cu" "F.Mask" "F.Paste")
			(net "PRSNT_CABLE_GPU_A2_ISO_R1_N")
		)
	)
)
